(kicad_pcb
	(version 20260206)
	(generator "pcbnew")
	(generator_version "10.0")
	(general
		(thickness 1.6)
		(legacy_teardrops no)
	)
	(paper "A4")
	(title_block
		(title "04192023_DAF0TMB3IC0_F0TG_MB_C_brd_V02_OCP.brd")
		(comment 1 "Grand Teton / footprint 3955 of 8354 (U25), pads 1876-1987 of 6102")
	)
	(layers
		(0 "F.Cu" signal "TOP")
		(4 "In1.Cu" signal "GND")
		(6 "In2.Cu" signal "IN1")
		(8 "In3.Cu" signal "GND1")
		(10 "In4.Cu" signal "IN2")
		(12 "In5.Cu" signal "GND2")
		(14 "In6.Cu" signal "IN3")
		(16 "In7.Cu" signal "GND3")
		(18 "In8.Cu" signal "VCC")
		(20 "In9.Cu" signal "VCC1")
		(22 "In10.Cu" signal "GND4")
		(24 "In11.Cu" signal "IN4")
		(26 "In12.Cu" signal "GND5")
		(28 "In13.Cu" signal "IN5")
		(30 "In14.Cu" signal "GND6")
		(32 "In15.Cu" signal "IN6")
		(34 "In16.Cu" signal "GND7")
		(2 "B.Cu" signal "BOTTOM")
		(9 "F.Adhes" user "F.Adhesive")
		(11 "B.Adhes" user "B.Adhesive")
		(13 "F.Paste" user "Package Geometry/Pastemask Top")
		(15 "B.Paste" user "Package Geometry/Pastemask Bottom")
		(5 "F.SilkS" user "Ref Des/Silkscreen Top")
		(7 "B.SilkS" user "Ref Des/Silkscreen Bottom")
		(1 "F.Mask" user "Board Geometry/Soldermask Top")
		(3 "B.Mask" user "Board Geometry/Soldermask Bottom")
		(17 "Dwgs.User" user "User.Drawings")
		(19 "Cmts.User" user "User.Comments")
		(21 "Eco1.User" user "User.Eco1")
		(23 "Eco2.User" user "User.Eco2")
		(25 "Edge.Cuts" user "Board Geometry/Outline")
		(27 "Margin" user)
		(31 "F.CrtYd" user "Package Geometry/Place Bound Top")
		(29 "B.CrtYd" user "Package Geometry/Place Bound Bottom")
		(35 "F.Fab" user "Ref Des/Assembly Top")
		(33 "B.Fab" user "Ref Des/Assembly Bottom")
	)
	(footprint ""
		(layer "F.Cu")
		(at 359.867962 -258.880102 180)
		(property "Reference" "U25"
			(at -45.78477 -62.086744 0)
			(unlocked yes)
			(layer "F.SilkS")
			(effects
				(font
					(size 0.7874 0.5842)
					(thickness 0.1524)
				)
			)
		)
		(property "Value" ""
			(at 0 0 180)
			(layer "F.Fab")
			(effects
				(font
					(size 1.27 1.27)
				)
			)
		)
		(duplicate_pad_numbers_are_jumpers no)
		(pad "BH9" smd circle
			(at -27.409902 3.599942 180)
			(size 0.450088 0.450088)
			(layers "F.Cu" "F.Mask" "F.Paste")
			(net "M_L_CPU0_SB_CA<2>")
		)
		(pad "BH10" smd circle
			(at -26.470102 3.599942 180)
			(size 0.450088 0.450088)
			(layers "F.Cu" "F.Mask" "F.Paste")
			(net "GND")
		)
		(pad "BH11" smd circle
			(at -25.530048 3.599942 180)
			(size 0.450088 0.450088)
			(layers "F.Cu" "F.Mask" "F.Paste")
			(net "M_L_CPU0_SB_CA<1>")
		)
		(pad "BH12" smd circle
			(at -24.589994 3.599942 180)
			(size 0.450088 0.450088)
			(layers "F.Cu" "F.Mask" "F.Paste")
			(net "GND")
		)
		(pad "BH13" smd circle
			(at -23.64994 3.599942 180)
			(size 0.450088 0.450088)
			(layers "F.Cu" "F.Mask" "F.Paste")
			(net "M_H_CPU0_SB_CA<2>")
		)
		(pad "BH14" smd circle
			(at -22.709886 3.599942 180)
			(size 0.450088 0.450088)
			(layers "F.Cu" "F.Mask" "F.Paste")
			(net "M_H_CPU0_SB_CA<1>")
		)
		(pad "BH15" smd circle
			(at -21.770086 3.599942 180)
			(size 0.450088 0.450088)
			(layers "F.Cu" "F.Mask" "F.Paste")
			(net "GND")
		)
		(pad "BH16" smd circle
			(at -20.830032 3.599942 180)
			(size 0.450088 0.450088)
			(layers "F.Cu" "F.Mask" "F.Paste")
			(net "M_J_CPU0_SB_CA<2>")
		)
		(pad "BH17" smd circle
			(at -19.889978 3.599942 180)
			(size 0.450088 0.450088)
			(layers "F.Cu" "F.Mask" "F.Paste")
			(net "GND")
		)
		(pad "BH18" smd circle
			(at -18.949924 3.599942 180)
			(size 0.450088 0.450088)
			(layers "F.Cu" "F.Mask" "F.Paste")
			(net "M_J_CPU0_SB_CA<1>")
		)
		(pad "BH19" smd circle
			(at -18.010124 3.599942 180)
			(size 0.450088 0.450088)
			(layers "F.Cu" "F.Mask" "F.Paste")
			(net "GND")
		)
		(pad "BH20" smd circle
			(at -17.07007 3.599942 180)
			(size 0.450088 0.450088)
			(layers "F.Cu" "F.Mask" "F.Paste")
			(net "M_I_CPU0_SB_CA<2>")
		)
		(pad "BH21" smd circle
			(at -16.130016 3.599942 180)
			(size 0.450088 0.450088)
			(layers "F.Cu" "F.Mask" "F.Paste")
			(net "M_I_CPU0_SB_CA<1>")
		)
		(pad "BH22" smd circle
			(at -15.189962 3.599942 180)
			(size 0.450088 0.450088)
			(layers "F.Cu" "F.Mask" "F.Paste")
			(net "GND")
		)
		(pad "BH23" smd circle
			(at -14.249908 3.599942 180)
			(size 0.450088 0.450088)
			(layers "F.Cu" "F.Mask" "F.Paste")
			(net "PVDDCR_SOC_P0")
		)
		(pad "BH24" smd circle
			(at -13.310108 3.599942 180)
			(size 0.450088 0.450088)
			(layers "F.Cu" "F.Mask" "F.Paste")
			(net "GND")
		)
		(pad "BH25" smd circle
			(at -12.370054 3.599942 180)
			(size 0.450088 0.450088)
			(layers "F.Cu" "F.Mask" "F.Paste")
			(net "PVDDCR_SOC_P0")
		)
		(pad "BH26" smd circle
			(at -11.43 3.599942 180)
			(size 0.450088 0.450088)
			(layers "F.Cu" "F.Mask" "F.Paste")
			(net "GND")
		)
		(pad "BH27" smd circle
			(at -10.489946 3.599942 180)
			(size 0.450088 0.450088)
			(layers "F.Cu" "F.Mask" "F.Paste")
			(net "PVDD18_S5_P0")
		)
		(pad "BH28" smd circle
			(at -9.549892 3.599942 180)
			(size 0.450088 0.450088)
			(layers "F.Cu" "F.Mask" "F.Paste")
			(net "GND")
		)
		(pad "BH48" smd circle
			(at 9.249918 3.599942 180)
			(size 0.450088 0.450088)
			(layers "F.Cu" "F.Mask" "F.Paste")
			(net "PVDDCR_SOC_P0")
		)
		(pad "BH49" smd circle
			(at 10.189972 3.599942 180)
			(size 0.450088 0.450088)
			(layers "F.Cu" "F.Mask" "F.Paste")
			(net "GND")
		)
		(pad "BH50" smd circle
			(at 11.130026 3.599942 180)
			(size 0.450088 0.450088)
			(layers "F.Cu" "F.Mask" "F.Paste")
			(net "GND")
		)
		(pad "BH51" smd circle
			(at 12.07008 3.599942 180)
			(size 0.450088 0.450088)
			(layers "F.Cu" "F.Mask" "F.Paste")
			(net "PVDDIO_P0")
		)
		(pad "BH52" smd circle
			(at 13.00988 3.599942 180)
			(size 0.450088 0.450088)
			(layers "F.Cu" "F.Mask" "F.Paste")
			(net "GND")
		)
		(pad "BH53" smd circle
			(at 13.949934 3.599942 180)
			(size 0.450088 0.450088)
			(layers "F.Cu" "F.Mask" "F.Paste")
			(net "PVDDIO_P0")
		)
		(pad "BH54" smd circle
			(at 14.889988 3.599942 180)
			(size 0.450088 0.450088)
			(layers "F.Cu" "F.Mask" "F.Paste")
			(net "GND")
		)
		(pad "BH55" smd circle
			(at 15.830042 3.599942 180)
			(size 0.450088 0.450088)
			(layers "F.Cu" "F.Mask" "F.Paste")
			(net "M_C_CPU0_SB_CA<1>")
		)
		(pad "BH56" smd circle
			(at 16.770096 3.599942 180)
			(size 0.450088 0.450088)
			(layers "F.Cu" "F.Mask" "F.Paste")
			(net "M_C_CPU0_SB_CA<2>")
		)
		(pad "BH57" smd circle
			(at 17.709896 3.599942 180)
			(size 0.450088 0.450088)
			(layers "F.Cu" "F.Mask" "F.Paste")
			(net "GND")
		)
		(pad "BH58" smd circle
			(at 18.64995 3.599942 180)
			(size 0.450088 0.450088)
			(layers "F.Cu" "F.Mask" "F.Paste")
			(net "M_D_CPU0_SB_CA<1>")
		)
		(pad "BH59" smd circle
			(at 19.590004 3.599942 180)
			(size 0.450088 0.450088)
			(layers "F.Cu" "F.Mask" "F.Paste")
			(net "GND")
		)
		(pad "BH60" smd circle
			(at 20.530058 3.599942 180)
			(size 0.450088 0.450088)
			(layers "F.Cu" "F.Mask" "F.Paste")
			(net "M_D_CPU0_SB_CA<2>")
		)
		(pad "BH61" smd circle
			(at 21.470112 3.599942 180)
			(size 0.450088 0.450088)
			(layers "F.Cu" "F.Mask" "F.Paste")
			(net "GND")
		)
		(pad "BH62" smd circle
			(at 22.409912 3.599942 180)
			(size 0.450088 0.450088)
			(layers "F.Cu" "F.Mask" "F.Paste")
			(net "M_B_CPU0_SB_CA<1>")
		)
		(pad "BH63" smd circle
			(at 23.349966 3.599942 180)
			(size 0.450088 0.450088)
			(layers "F.Cu" "F.Mask" "F.Paste")
			(net "M_B_CPU0_SB_CA<2>")
		)
		(pad "BH64" smd circle
			(at 24.29002 3.599942 180)
			(size 0.450088 0.450088)
			(layers "F.Cu" "F.Mask" "F.Paste")
			(net "GND")
		)
		(pad "BH65" smd circle
			(at 25.230074 3.599942 180)
			(size 0.450088 0.450088)
			(layers "F.Cu" "F.Mask" "F.Paste")
			(net "M_F_CPU0_SB_CA<1>")
		)
		(pad "BH66" smd circle
			(at 26.170128 3.599942 180)
			(size 0.450088 0.450088)
			(layers "F.Cu" "F.Mask" "F.Paste")
			(net "GND")
		)
		(pad "BH67" smd circle
			(at 27.109928 3.599942 180)
			(size 0.450088 0.450088)
			(layers "F.Cu" "F.Mask" "F.Paste")
			(net "M_F_CPU0_SB_CA<2>")
		)
		(pad "BH68" smd circle
			(at 28.049982 3.599942 180)
			(size 0.450088 0.450088)
			(layers "F.Cu" "F.Mask" "F.Paste")
			(net "GND")
		)
		(pad "BH69" smd circle
			(at 28.990036 3.599942 180)
			(size 0.450088 0.450088)
			(layers "F.Cu" "F.Mask" "F.Paste")
			(net "M_E_CPU0_SB_CA<1>")
		)
		(pad "BH70" smd circle
			(at 29.93009 3.599942 180)
			(size 0.450088 0.450088)
			(layers "F.Cu" "F.Mask" "F.Paste")
			(net "M_E_CPU0_SB_CA<2>")
		)
		(pad "BH71" smd circle
			(at 30.86989 3.599942 180)
			(size 0.450088 0.450088)
			(layers "F.Cu" "F.Mask" "F.Paste")
			(net "GND")
		)
		(pad "BH72" smd circle
			(at 31.809944 3.599942 180)
			(size 0.450088 0.450088)
			(layers "F.Cu" "F.Mask" "F.Paste")
			(net "M_A_CPU0_SB_CA<1>")
		)
		(pad "BH73" smd circle
			(at 32.749998 3.599942 180)
			(size 0.450088 0.450088)
			(layers "F.Cu" "F.Mask" "F.Paste")
			(net "GND")
		)
		(pad "BH74" smd circle
			(at 33.690052 3.599942 180)
			(size 0.450088 0.450088)
			(layers "F.Cu" "F.Mask" "F.Paste")
			(net "M_A_CPU0_SB_CA<2>")
		)
		(pad "BJ1" smd circle
			(at -34.459926 4.409948 180)
			(size 0.450088 0.450088)
			(layers "F.Cu" "F.Mask" "F.Paste")
			(net "GND")
		)
		(pad "BJ2" smd circle
			(at -33.519872 4.409948 180)
			(size 0.450088 0.450088)
			(layers "F.Cu" "F.Mask" "F.Paste")
			(net "M_G_CPU0_SB_CA<3>")
		)
		(pad "BJ3" smd circle
			(at -32.580072 4.409948 180)
			(size 0.450088 0.450088)
			(layers "F.Cu" "F.Mask" "F.Paste")
			(net "M_G_CPU0_SB_CA<4>")
		)
		(pad "BJ4" smd circle
			(at -31.640018 4.409948 180)
			(size 0.450088 0.450088)
			(layers "F.Cu" "F.Mask" "F.Paste")
			(net "PVDDCR_SOC_P0")
		)
		(pad "BJ5" smd circle
			(at -30.699964 4.409948 180)
			(size 0.450088 0.450088)
			(layers "F.Cu" "F.Mask" "F.Paste")
			(net "M_K_CPU0_SB_CA<3>")
		)
		(pad "BJ6" smd circle
			(at -29.75991 4.409948 180)
			(size 0.450088 0.450088)
			(layers "F.Cu" "F.Mask" "F.Paste")
			(net "GND")
		)
		(pad "BJ7" smd circle
			(at -28.82011 4.409948 180)
			(size 0.450088 0.450088)
			(layers "F.Cu" "F.Mask" "F.Paste")
			(net "M_K_CPU0_SB_CA<4>")
		)
		(pad "BJ8" smd circle
			(at -27.880056 4.409948 180)
			(size 0.450088 0.450088)
			(layers "F.Cu" "F.Mask" "F.Paste")
			(net "GND")
		)
		(pad "BJ9" smd circle
			(at -26.940002 4.409948 180)
			(size 0.450088 0.450088)
			(layers "F.Cu" "F.Mask" "F.Paste")
			(net "M_L_CPU0_SB_CA<3>")
		)
		(pad "BJ10" smd circle
			(at -25.999948 4.409948 180)
			(size 0.450088 0.450088)
			(layers "F.Cu" "F.Mask" "F.Paste")
			(net "M_L_CPU0_SB_CA<4>")
		)
		(pad "BJ11" smd circle
			(at -25.059894 4.409948 180)
			(size 0.450088 0.450088)
			(layers "F.Cu" "F.Mask" "F.Paste")
			(net "PVDDCR_SOC_P0")
		)
		(pad "BJ12" smd circle
			(at -24.120094 4.409948 180)
			(size 0.450088 0.450088)
			(layers "F.Cu" "F.Mask" "F.Paste")
			(net "M_H_CPU0_SB_CA<3>")
		)
		(pad "BJ13" smd circle
			(at -23.18004 4.409948 180)
			(size 0.450088 0.450088)
			(layers "F.Cu" "F.Mask" "F.Paste")
			(net "GND")
		)
		(pad "BJ14" smd circle
			(at -22.239986 4.409948 180)
			(size 0.450088 0.450088)
			(layers "F.Cu" "F.Mask" "F.Paste")
			(net "M_H_CPU0_SB_CA<4>")
		)
		(pad "BJ15" smd circle
			(at -21.299932 4.409948 180)
			(size 0.450088 0.450088)
			(layers "F.Cu" "F.Mask" "F.Paste")
			(net "GND")
		)
		(pad "BJ16" smd circle
			(at -20.359878 4.409948 180)
			(size 0.450088 0.450088)
			(layers "F.Cu" "F.Mask" "F.Paste")
			(net "M_J_CPU0_SB_CA<3>")
		)
		(pad "BJ17" smd circle
			(at -19.420078 4.409948 180)
			(size 0.450088 0.450088)
			(layers "F.Cu" "F.Mask" "F.Paste")
			(net "M_J_CPU0_SB_CA<4>")
		)
		(pad "BJ18" smd circle
			(at -18.480024 4.409948 180)
			(size 0.450088 0.450088)
			(layers "F.Cu" "F.Mask" "F.Paste")
			(net "PVDD11_S3_P0")
		)
		(pad "BJ19" smd circle
			(at -17.53997 4.409948 180)
			(size 0.450088 0.450088)
			(layers "F.Cu" "F.Mask" "F.Paste")
			(net "M_I_CPU0_SB_CA<3>")
		)
		(pad "BJ20" smd circle
			(at -16.599916 4.409948 180)
			(size 0.450088 0.450088)
			(layers "F.Cu" "F.Mask" "F.Paste")
			(net "GND")
		)
		(pad "BJ21" smd circle
			(at -15.660116 4.409948 180)
			(size 0.450088 0.450088)
			(layers "F.Cu" "F.Mask" "F.Paste")
			(net "M_I_CPU0_SB_CA<4>")
		)
		(pad "BJ22" smd circle
			(at -14.720062 4.409948 180)
			(size 0.450088 0.450088)
			(layers "F.Cu" "F.Mask" "F.Paste")
			(net "GND")
		)
		(pad "BJ23" smd circle
			(at -13.780008 4.409948 180)
			(size 0.450088 0.450088)
			(layers "F.Cu" "F.Mask" "F.Paste")
			(net "PVDD11_S3_P0")
		)
		(pad "BJ24" smd circle
			(at -12.839954 4.409948 180)
			(size 0.450088 0.450088)
			(layers "F.Cu" "F.Mask" "F.Paste")
			(net "GND")
		)
		(pad "BJ25" smd circle
			(at -11.8999 4.409948 180)
			(size 0.450088 0.450088)
			(layers "F.Cu" "F.Mask" "F.Paste")
			(net "PVDD11_S3_P0")
		)
		(pad "BJ26" smd circle
			(at -10.9601 4.409948 180)
			(size 0.450088 0.450088)
			(layers "F.Cu" "F.Mask" "F.Paste")
			(net "GND")
		)
		(pad "BJ27" smd circle
			(at -10.020046 4.409948 180)
			(size 0.450088 0.450088)
			(layers "F.Cu" "F.Mask" "F.Paste")
			(net "PVDD11_S3_P0")
		)
		(pad "BJ28" smd circle
			(at -9.079992 4.409948 180)
			(size 0.450088 0.450088)
			(layers "F.Cu" "F.Mask" "F.Paste")
			(net "GND")
		)
		(pad "BJ48" smd circle
			(at 8.780018 4.409948 180)
			(size 0.450088 0.450088)
			(layers "F.Cu" "F.Mask" "F.Paste")
			(net "PVDDCR_SOC_P0")
		)
		(pad "BJ49" smd circle
			(at 9.720072 4.409948 180)
			(size 0.450088 0.450088)
			(layers "F.Cu" "F.Mask" "F.Paste")
			(net "GND")
		)
		(pad "BJ50" smd circle
			(at 10.659872 4.409948 180)
			(size 0.450088 0.450088)
			(layers "F.Cu" "F.Mask" "F.Paste")
			(net "PVDDIO_P0")
		)
		(pad "BJ51" smd circle
			(at 11.599926 4.409948 180)
			(size 0.450088 0.450088)
			(layers "F.Cu" "F.Mask" "F.Paste")
			(net "GND")
		)
		(pad "BJ52" smd circle
			(at 12.53998 4.409948 180)
			(size 0.450088 0.450088)
			(layers "F.Cu" "F.Mask" "F.Paste")
			(net "PVDDIO_P0")
		)
		(pad "BJ53" smd circle
			(at 13.480034 4.409948 180)
			(size 0.450088 0.450088)
			(layers "F.Cu" "F.Mask" "F.Paste")
			(net "GND")
		)
		(pad "BJ54" smd circle
			(at 14.420088 4.409948 180)
			(size 0.450088 0.450088)
			(layers "F.Cu" "F.Mask" "F.Paste")
			(net "PVDDIO_P0")
		)
		(pad "BJ55" smd circle
			(at 15.359888 4.409948 180)
			(size 0.450088 0.450088)
			(layers "F.Cu" "F.Mask" "F.Paste")
			(net "M_C_CPU0_SB_CA<4>")
		)
		(pad "BJ56" smd circle
			(at 16.299942 4.409948 180)
			(size 0.450088 0.450088)
			(layers "F.Cu" "F.Mask" "F.Paste")
			(net "GND")
		)
		(pad "BJ57" smd circle
			(at 17.239996 4.409948 180)
			(size 0.450088 0.450088)
			(layers "F.Cu" "F.Mask" "F.Paste")
			(net "M_C_CPU0_SB_CA<3>")
		)
		(pad "BJ58" smd circle
			(at 18.18005 4.409948 180)
			(size 0.450088 0.450088)
			(layers "F.Cu" "F.Mask" "F.Paste")
			(net "PVDDIO_P0")
		)
		(pad "BJ59" smd circle
			(at 19.120104 4.409948 180)
			(size 0.450088 0.450088)
			(layers "F.Cu" "F.Mask" "F.Paste")
			(net "M_D_CPU0_SB_CA<4>")
		)
		(pad "BJ60" smd circle
			(at 20.059904 4.409948 180)
			(size 0.450088 0.450088)
			(layers "F.Cu" "F.Mask" "F.Paste")
			(net "M_D_CPU0_SB_CA<3>")
		)
		(pad "BJ61" smd circle
			(at 20.999958 4.409948 180)
			(size 0.450088 0.450088)
			(layers "F.Cu" "F.Mask" "F.Paste")
			(net "GND")
		)
		(pad "BJ62" smd circle
			(at 21.940012 4.409948 180)
			(size 0.450088 0.450088)
			(layers "F.Cu" "F.Mask" "F.Paste")
			(net "M_B_CPU0_SB_CA<4>")
		)
		(pad "BJ63" smd circle
			(at 22.880066 4.409948 180)
			(size 0.450088 0.450088)
			(layers "F.Cu" "F.Mask" "F.Paste")
			(net "GND")
		)
		(pad "BJ64" smd circle
			(at 23.82012 4.409948 180)
			(size 0.450088 0.450088)
			(layers "F.Cu" "F.Mask" "F.Paste")
			(net "M_B_CPU0_SB_CA<3>")
		)
		(pad "BJ65" smd circle
			(at 24.75992 4.409948 180)
			(size 0.450088 0.450088)
			(layers "F.Cu" "F.Mask" "F.Paste")
			(net "PVDDIO_P0")
		)
		(pad "BJ66" smd circle
			(at 25.699974 4.409948 180)
			(size 0.450088 0.450088)
			(layers "F.Cu" "F.Mask" "F.Paste")
			(net "M_F_CPU0_SB_CA<4>")
		)
		(pad "BJ67" smd circle
			(at 26.640028 4.409948 180)
			(size 0.450088 0.450088)
			(layers "F.Cu" "F.Mask" "F.Paste")
			(net "M_F_CPU0_SB_CA<3>")
		)
		(pad "BJ68" smd circle
			(at 27.580082 4.409948 180)
			(size 0.450088 0.450088)
			(layers "F.Cu" "F.Mask" "F.Paste")
			(net "GND")
		)
		(pad "BJ69" smd circle
			(at 28.519882 4.409948 180)
			(size 0.450088 0.450088)
			(layers "F.Cu" "F.Mask" "F.Paste")
			(net "M_E_CPU0_SB_CA<4>")
		)
		(pad "BJ70" smd circle
			(at 29.459936 4.409948 180)
			(size 0.450088 0.450088)
			(layers "F.Cu" "F.Mask" "F.Paste")
			(net "GND")
		)
		(pad "BJ71" smd circle
			(at 30.39999 4.409948 180)
			(size 0.450088 0.450088)
			(layers "F.Cu" "F.Mask" "F.Paste")
			(net "M_E_CPU0_SB_CA<3>")
		)
		(pad "BJ72" smd circle
			(at 31.340044 4.409948 180)
			(size 0.450088 0.450088)
			(layers "F.Cu" "F.Mask" "F.Paste")
			(net "PVDDIO_P0")
		)
		(pad "BJ73" smd circle
			(at 32.280098 4.409948 180)
			(size 0.450088 0.450088)
			(layers "F.Cu" "F.Mask" "F.Paste")
			(net "M_A_CPU0_SB_CA<4>")
		)
		(pad "BJ74" smd circle
			(at 33.219898 4.409948 180)
			(size 0.450088 0.450088)
			(layers "F.Cu" "F.Mask" "F.Paste")
			(net "M_A_CPU0_SB_CA<3>")
		)
		(pad "BJ75" smd circle
			(at 34.159952 4.409948 180)
			(size 0.450088 0.450088)
			(layers "F.Cu" "F.Mask" "F.Paste")
			(net "GND")
		)
		(pad "BK2" smd circle
			(at -33.990026 5.219954 180)
			(size 0.450088 0.450088)
			(layers "F.Cu" "F.Mask" "F.Paste")
			(net "M_G_CPU0_SB_CA<6>")
		)
		(pad "BK3" smd circle
			(at -33.049972 5.219954 180)
			(size 0.450088 0.450088)
			(layers "F.Cu" "F.Mask" "F.Paste")
			(net "GND")
		)
		(pad "BK4" smd circle
			(at -32.109918 5.219954 180)
			(size 0.450088 0.450088)
			(layers "F.Cu" "F.Mask" "F.Paste")
			(net "M_G_CPU0_SB_CA<5>")
		)
		(pad "BK5" smd circle
			(at -31.170118 5.219954 180)
			(size 0.450088 0.450088)
			(layers "F.Cu" "F.Mask" "F.Paste")
			(net "GND")
		)
		(pad "BK6" smd circle
			(at -30.230064 5.219954 180)
			(size 0.450088 0.450088)
			(layers "F.Cu" "F.Mask" "F.Paste")
			(net "M_K_CPU0_SB_CA<6>")
		)
		(pad "BK7" smd circle
			(at -29.29001 5.219954 180)
			(size 0.450088 0.450088)
			(layers "F.Cu" "F.Mask" "F.Paste")
			(net "M_K_CPU0_SB_CA<5>")
		)
		(pad "BK8" smd circle
			(at -28.349956 5.219954 180)
			(size 0.450088 0.450088)
			(layers "F.Cu" "F.Mask" "F.Paste")
			(net "GND")
		)
		(pad "BK9" smd circle
			(at -27.409902 5.219954 180)
			(size 0.450088 0.450088)
			(layers "F.Cu" "F.Mask" "F.Paste")
			(net "M_L_CPU0_SB_CA<6>")
		)
		(pad "BK10" smd circle
			(at -26.470102 5.219954 180)
			(size 0.450088 0.450088)
			(layers "F.Cu" "F.Mask" "F.Paste")
			(net "GND")
		)
	)
)
